(kicad_pcb
	(version 20241229)
	(generator "pcbnew")
	(generator_version "9.0")
	(general
		(thickness 0.876)
		(legacy_teardrops no)
	)
	(paper "A4")
	(title_block
		(rev "1.2.2")
		(comment 9 "footprints 19-19 of 20")
	)
	(layers
		(0 "F.Cu" signal)
		(4 "In1.Cu" signal)
		(6 "In2.Cu" signal)
		(2 "B.Cu" signal)
		(9 "F.Adhes" user "F.Adhesive")
		(11 "B.Adhes" user "B.Adhesive")
		(13 "F.Paste" user)
		(15 "B.Paste" user)
		(5 "F.SilkS" user "F.Silkscreen")
		(7 "B.SilkS" user "B.Silkscreen")
		(1 "F.Mask" user)
		(3 "B.Mask" user)
		(17 "Dwgs.User" user "User.Drawings")
		(19 "Cmts.User" user "User.Comments")
		(21 "Eco1.User" user "User.Eco1")
		(23 "Eco2.User" user "User.Eco2")
		(25 "Edge.Cuts" user)
		(27 "Margin" user)
		(31 "F.CrtYd" user "F.Courtyard")
		(29 "B.CrtYd" user "B.Courtyard")
		(35 "F.Fab" user)
		(33 "B.Fab" user)
	)
	(footprint "antmicro-footprints:oshw-logo"
		(layer "B.Cu")
		(at 159.170059 92.357277 180)
		(descr "OSHW Logo")
		(tags "OSHW Logo")
		(property "Reference" "N2"
			(at -3.08 4.76 0)
			(layer "B.SilkS")
			(hide yes)
			(effects
				(font
					(size 0.7 0.7)
					(thickness 0.15)
				)
				(justify mirror)
			)
		)
		(property "Value" "oshw_logo"
			(at 3.43 4.88 0)
			(layer "B.Fab")
			(hide yes)
			(effects
				(font
					(size 0.7 0.7)
					(thickness 0.15)
				)
				(justify mirror)
			)
		)
		(property "Description" "Mechanical part"
			(at 0 0 180)
			(layer "F.Fab")
			(hide yes)
			(effects
				(font
					(size 1.27 1.27)
					(thickness 0.15)
				)
			)
		)
		(property "Author" "Antmicro"
			(at 318.340118 184.714554 0)
			(layer "B.Fab")
			(hide yes)
			(effects
				(font
					(size 1 1)
					(thickness 0.15)
				)
				(justify mirror)
			)
		)
		(property "License" "Apache-2.0"
			(at 318.340118 184.714554 0)
			(layer "B.Fab")
			(hide yes)
			(effects
				(font
					(size 1 1)
					(thickness 0.15)
				)
				(justify mirror)
			)
		)
		(property "MPN" ""
			(at 318.340118 184.714554 0)
			(layer "B.Fab")
			(hide yes)
			(effects
				(font
					(size 1 1)
					(thickness 0.15)
				)
				(justify mirror)
			)
		)
		(property "Manufacturer" ""
			(at 318.340118 184.714554 0)
			(layer "B.Fab")
			(hide yes)
			(effects
				(font
					(size 1 1)
					(thickness 0.15)
				)
				(justify mirror)
			)
		)
		(property "Public" "False"
			(at 318.340118 184.714554 0)
			(layer "B.Fab")
			(hide yes)
			(effects
				(font
					(size 1 1)
					(thickness 0.15)
				)
				(justify mirror)
			)
		)
		(sheetname "/")
		(sheetfile "m2-pcie-adapter.kicad_sch")
		(attr exclude_from_pos_files allow_soldermask_bridges)
	)
)
